# TIMECARD (Time Appliance Project (Time Card)) — schematic netlist excerpt (pin names and nets, part order shuffled) for the footprints in the layout excerpt that follows; sources: Cadence DE-HDL packaged netlist, KiCad conversion of R4006-B0001-02_R01.brd

C7  CAPACITOR  0.1UF 25V 10%  pkg SMC_0402R_H022  page 27 : \1\ = XP12R0V_A_IMON ; \2\ = SG
MAC_PIN1  NUT  pkg P_NUT_079C100  page 21 : \1\ = ANALOG_TUNING_IN

(kicad_pcb
	(version 20260206)
	(generator "pcbnew")
	(generator_version "10.0")
	(general
		(thickness 1.6)
		(legacy_teardrops no)
	)
	(paper "A4")
	(title_block
		(title "timecard-production-celestica-r4006 — R4006-B0001-02_R01.brd")
		(comment 1 "Time Appliance Project (Time Card) / footprints 234-235 of 1113")
	)
	(layers
		(0 "F.Cu" signal "TOP")
		(4 "In1.Cu" signal "L02_GND1")
		(6 "In2.Cu" signal "L03_SIG1")
		(8 "In3.Cu" signal "L04_GND2")
		(10 "In4.Cu" signal "L05_VCC1")
		(12 "In5.Cu" signal "L06_VCC2")
		(14 "In6.Cu" signal "L07_GND3")
		(16 "In7.Cu" signal "L08_SIG2")
		(18 "In8.Cu" signal "L09_GND4")
		(2 "B.Cu" signal "BOTTOM")
		(9 "F.Adhes" user "F.Adhesive")
		(11 "B.Adhes" user "B.Adhesive")
		(13 "F.Paste" user "Package Geometry/Pastemask Top")
		(15 "B.Paste" user "Package Geometry/Pastemask Bottom")
		(5 "F.SilkS" user "Ref Des/Silkscreen Top")
		(7 "B.SilkS" user "Ref Des/Silkscreen Bottom")
		(1 "F.Mask" user "Board Geometry/Soldermask Top")
		(3 "B.Mask" user "Board Geometry/Soldermask Bottom")
		(17 "Dwgs.User" user "User.Drawings")
		(19 "Cmts.User" user "User.Comments")
		(21 "Eco1.User" user "User.Eco1")
		(23 "Eco2.User" user "User.Eco2")
		(25 "Edge.Cuts" user "Board Geometry/Outline")
		(27 "Margin" user)
		(31 "F.CrtYd" user "Package Geometry/Place Bound Top")
		(29 "B.CrtYd" user "Package Geometry/Place Bound Bottom")
		(35 "F.Fab" user "Ref Des/Assembly Top")
		(33 "B.Fab" user "Ref Des/Assembly Bottom")
	)
	(footprint ""
		(layer "F.Cu")
		(at 32.021018 -67.066922)
		(property "Reference" "MAC_PIN1"
			(at 0.127762 2.834132 0)
			(unlocked yes)
			(layer "F.SilkS")
			(effects
				(font
					(size 0.7874 0.5842)
					(thickness 0.1524)
				)
			)
		)
		(property "Value" ""
			(at 0 0 0)
			(layer "F.Fab")
			(effects
				(font
					(size 1.27 1.27)
				)
			)
		)
		(property "Device Type" "NUT-A200-00029-FB"
			(at 0 2.632964 0)
			(unlocked yes)
			(layer "F.Fab")
			(hide yes)
			(effects
				(font
					(size 0.7874 0.5842)
					(thickness 0.1524)
				)
			)
		)
		(property "User Part Number" "PARTNUM*"
			(at 0 3.826764 0)
			(unlocked yes)
			(layer "Cmts.User")
			(hide yes)
			(effects
				(font
					(size 0.7874 0.5842)
					(thickness 0.1524)
				)
			)
		)
		(duplicate_pad_numbers_are_jumpers no)
		(fp_circle
			(center 0 0)
			(end 1.524 0)
			(stroke
				(width 0.1)
				(type default)
			)
			(fill no)
			(layer "F.SilkS")
		)
		(fp_poly
			(pts
				(arc
					(start -1.260856 -0.1524)
					(mid -0.898049 -0.898049)
					(end -0.1524 -1.260856)
				)
				(arc
					(start -0.1524 -0.991616)
					(mid -0.709411 -0.709411)
					(end -0.991616 -0.1524)
				)
			)
			(stroke
				(width 0)
				(type default)
			)
			(fill yes)
			(layer "F.Paste")
		)
		(fp_poly
			(pts
				(arc
					(start -0.1524 1.260856)
					(mid -0.898049 0.898049)
					(end -1.260856 0.1524)
				)
				(arc
					(start -0.991616 0.1524)
					(mid -0.709411 0.709411)
					(end -0.1524 0.991616)
				)
			)
			(stroke
				(width 0)
				(type default)
			)
			(fill yes)
			(layer "F.Paste")
		)
		(fp_poly
			(pts
				(arc
					(start 0.1524 -1.260856)
					(mid 0.898049 -0.898049)
					(end 1.260856 -0.1524)
				)
				(arc
					(start 0.991616 -0.1524)
					(mid 0.709411 -0.709411)
					(end 0.1524 -0.991616)
				)
			)
			(stroke
				(width 0)
				(type default)
			)
			(fill yes)
			(layer "F.Paste")
		)
		(fp_poly
			(pts
				(arc
					(start 1.260856 0.1524)
					(mid 0.898049 0.898049)
					(end 0.1524 1.260856)
				)
				(arc
					(start 0.1524 0.991616)
					(mid 0.709411 0.709411)
					(end 0.991616 0.1524)
				)
			)
			(stroke
				(width 0)
				(type default)
			)
			(fill yes)
			(layer "F.Paste")
		)
		(fp_poly
			(pts
				(arc
					(start 6.35 0)
					(mid -6.35 0)
					(end 6.35 0)
				)
			)
			(stroke
				(width 0)
				(type default)
			)
			(fill no)
			(layer "B.CrtYd")
		)
		(fp_poly
			(pts
				(arc
					(start 1.778 0)
					(mid -1.778 0)
					(end 1.778 0)
				)
			)
			(stroke
				(width 0)
				(type default)
			)
			(fill no)
			(layer "F.CrtYd")
		)
		(fp_circle
			(center 0 0)
			(end 1.1684 0)
			(stroke
				(width 0.1)
				(type default)
			)
			(fill no)
			(layer "F.Fab")
		)
		(pad "1" thru_hole circle
			(at 0 0)
			(size 2.54 2.54)
			(drill 2.0066)
			(layers "*.Cu" "*.Mask")
			(remove_unused_layers no)
			(net "ANALOG_TUNING_IN")
			(thermal_gap 0.0254)
			(padstack
				(mode front_inner_back)
				(layer "Inner"
					(shape circle)
					(size 2.54 2.54)
					(clearance 0.0254)
				)
				(layer "B.Cu"
					(shape circle)
					(size 2.54 2.54)
				)
			)
		)
	)
	(footprint ""
		(layer "F.Cu")
		(at 145.8214 -97.9678)
		(property "Reference" "C7"
			(at 2.6416 -0.41783 0)
			(unlocked yes)
			(layer "F.SilkS")
			(effects
				(font
					(size 0.7874 0.5842)
					(thickness 0.1524)
				)
			)
		)
		(property "Value" "VAL*"
			(at 0.0762 2.067306 0)
			(unlocked yes)
			(layer "F.Fab")
			(hide yes)
			(effects
				(font
					(size 0.7874 0.5842)
					(thickness 0.1524)
				)
			)
		)
		(property "Device Type" "CAPACITOR-G105-0B104-EK,0.1UF,A"
			(at 0.0508 1.127506 0)
			(unlocked yes)
			(layer "F.Fab")
			(hide yes)
			(effects
				(font
					(size 0.7874 0.5842)
					(thickness 0.1524)
				)
			)
		)
		(property "User Part Number" "PARTNUM*"
			(at 0.1016 4.023106 0)
			(unlocked yes)
			(layer "Cmts.User")
			(hide yes)
			(effects
				(font
					(size 0.7874 0.5842)
					(thickness 0.1524)
				)
			)
		)
		(property "Tolerance" "TOL*"
			(at 0.0762 3.032506 0)
			(unlocked yes)
			(layer "Cmts.User")
			(hide yes)
			(effects
				(font
					(size 0.7874 0.5842)
					(thickness 0.1524)
				)
			)
		)
		(duplicate_pad_numbers_are_jumpers no)
		(fp_line
			(start -1.143 -0.5588)
			(end -1.143 0.5588)
			(stroke
				(width 0.1)
				(type default)
			)
			(layer "F.SilkS")
		)
		(fp_line
			(start -1.143 0.5588)
			(end 1.143 0.5588)
			(stroke
				(width 0.1)
				(type default)
			)
			(layer "F.SilkS")
		)
		(fp_line
			(start 1.143 -0.5588)
			(end -1.143 -0.5588)
			(stroke
				(width 0.1)
				(type default)
			)
			(layer "F.SilkS")
		)
		(fp_line
			(start 1.143 0.5588)
			(end 1.143 -0.5588)
			(stroke
				(width 0.1)
				(type default)
			)
			(layer "F.SilkS")
		)
		(fp_rect
			(start -1.143 0.5588)
			(end 1.143 -0.5588)
			(stroke
				(width 0)
				(type default)
			)
			(fill no)
			(layer "F.CrtYd")
		)
		(fp_line
			(start -0.508 -0.3048)
			(end -0.508 0.3048)
			(stroke
				(width 0.1)
				(type default)
			)
			(layer "F.Fab")
		)
		(fp_line
			(start -0.508 0.3048)
			(end 0.508 0.3048)
			(stroke
				(width 0.1)
				(type default)
			)
			(layer "F.Fab")
		)
		(fp_line
			(start 0.508 -0.3048)
			(end -0.508 -0.3048)
			(stroke
				(width 0.1)
				(type default)
			)
			(layer "F.Fab")
		)
		(fp_line
			(start 0.508 0.3048)
			(end 0.508 -0.3048)
			(stroke
				(width 0.1)
				(type default)
			)
			(layer "F.Fab")
		)
		(pad "1" smd rect
			(at -0.5334 0)
			(size 0.7112 0.6096)
			(layers "F.Cu" "F.Mask" "F.Paste")
			(net "XP12R0V_A_IMON")
		)
		(pad "2" smd rect
			(at 0.5334 0)
			(size 0.7112 0.6096)
			(layers "F.Cu" "F.Mask" "F.Paste")
			(net "SG")
		)
		(zone
			(layer "F.Cu")
			(hatch none 0.5)
			(connect_pads
				(clearance 0)
			)
			(min_thickness 0.25)
			(keepout
				(tracks allowed)
				(vias not_allowed)
				(pads allowed)
				(copperpour not_allowed)
				(footprints allowed)
			)
			(placement
				(enabled no)
				(sheetname "")
			)
			(fill
				(thermal_gap 0.5)
				(thermal_bridge_width 0.5)
				(island_removal_mode 0)
			)
			(polygon
				(pts
					(xy 145.7452 -97.663) (xy 145.8976 -97.663) (xy 145.8976 -98.2726) (xy 145.7452 -98.2726)
				)
			)
		)
	)
)
